# S9S_MB_2U (Grand Teton) — schematic netlist excerpt (pin names and nets, part order shuffled) for the footprints in the layout excerpt that follows; sources: Cadence DE-HDL packaged netlist, KiCad conversion of 03242023_DA0F0TMBIJ0_F0T_Motherboard_J_brd_V01_OCP.brd

R2486  Q_RES  10K 1% CHIP  pkg 0402LF  page 244 : A = P3V3_AUX ; B = PWRGD_P3V3_AUX_R2
C908  Q_CAP_DIFFBUS  DIFF BUS_0.22UF 6.3V 20% X6S  pkg C0201  page 173 : \1\ = P5E_CPU0_PE0_TX_C_DN<12> ; \2\ = P5E_CPU0_PE0_TX_DN<12>
R3392  Q_RES  49.9 1% CHIP  pkg 0402LF  page 149 : A = GPU_BASE_STBY_EN_BUF_R ; B = GPU_BASE_STBY_EN_BUF

(kicad_pcb
	(version 20260206)
	(generator "pcbnew")
	(generator_version "10.0")
	(general
		(thickness 1.6)
		(legacy_teardrops no)
	)
	(paper "A4")
	(title_block
		(title "03242023_DA0F0TMBIJ0_F0T_Motherboard_J_brd_V01_OCP.brd")
		(comment 1 "Grand Teton / footprints 2723-2725 of 6105")
	)
	(layers
		(0 "F.Cu" signal "TOP")
		(4 "In1.Cu" signal "GND")
		(6 "In2.Cu" signal "IN1")
		(8 "In3.Cu" signal "GND1")
		(10 "In4.Cu" signal "IN2")
		(12 "In5.Cu" signal "GND2")
		(14 "In6.Cu" signal "IN3")
		(16 "In7.Cu" signal "GND3")
		(18 "In8.Cu" signal "VCC")
		(20 "In9.Cu" signal "VCC1")
		(22 "In10.Cu" signal "GND4")
		(24 "In11.Cu" signal "IN4")
		(26 "In12.Cu" signal "GND5")
		(28 "In13.Cu" signal "IN5")
		(30 "In14.Cu" signal "GND6")
		(32 "In15.Cu" signal "IN6")
		(34 "In16.Cu" signal "GND7")
		(2 "B.Cu" signal "BOTTOM")
		(9 "F.Adhes" user "F.Adhesive")
		(11 "B.Adhes" user "B.Adhesive")
		(13 "F.Paste" user "Package Geometry/Pastemask Top")
		(15 "B.Paste" user "Package Geometry/Pastemask Bottom")
		(5 "F.SilkS" user "Ref Des/Silkscreen Top")
		(7 "B.SilkS" user "Ref Des/Silkscreen Bottom")
		(1 "F.Mask" user "Board Geometry/Soldermask Top")
		(3 "B.Mask" user "Board Geometry/Soldermask Bottom")
		(17 "Dwgs.User" user "User.Drawings")
		(19 "Cmts.User" user "User.Comments")
		(21 "Eco1.User" user "User.Eco1")
		(23 "Eco2.User" user "User.Eco2")
		(25 "Edge.Cuts" user "Board Geometry/Outline")
		(27 "Margin" user)
		(31 "F.CrtYd" user "Package Geometry/Place Bound Top")
		(29 "B.CrtYd" user "Package Geometry/Place Bound Bottom")
		(35 "F.Fab" user "Ref Des/Assembly Top")
		(33 "B.Fab" user "Ref Des/Assembly Bottom")
	)
	(footprint ""
		(layer "F.Cu")
		(at 314.490608 -408.517344 -90)
		(property "Reference" "C908"
			(at 0 0 270)
			(layer "F.SilkS")
			(hide yes)
			(effects
				(font
					(size 1.27 1.27)
				)
			)
		)
		(property "Value" ""
			(at 0 0 270)
			(layer "F.Fab")
			(effects
				(font
					(size 1.27 1.27)
				)
			)
		)
		(duplicate_pad_numbers_are_jumpers no)
		(fp_line
			(start -0.299974 0.150114)
			(end -0.299974 -0.150114)
			(stroke
				(width 0.1)
				(type default)
			)
			(layer "F.Fab")
		)
		(fp_line
			(start 0.299974 0.150114)
			(end -0.299974 0.150114)
			(stroke
				(width 0.1)
				(type default)
			)
			(layer "F.Fab")
		)
		(fp_line
			(start -0.299974 -0.150114)
			(end 0.299974 -0.150114)
			(stroke
				(width 0.1)
				(type default)
			)
			(layer "F.Fab")
		)
		(fp_line
			(start 0.299974 -0.150114)
			(end 0.299974 0.150114)
			(stroke
				(width 0.1)
				(type default)
			)
			(layer "F.Fab")
		)
		(pad "1" smd rect
			(at -0.2667 0 270)
			(size 0.3048 0.381)
			(layers "F.Cu" "F.Mask" "F.Paste")
			(net "P5E_CPU0_PE0_TX_C_DN<12>")
		)
		(pad "2" smd rect
			(at 0.2667 0 270)
			(size 0.3048 0.381)
			(layers "F.Cu" "F.Mask" "F.Paste")
			(net "P5E_CPU0_PE0_TX_DN<12>")
		)
	)
	(footprint ""
		(layer "F.Cu")
		(at 161.21888 -133.695948 180)
		(property "Reference" "R2486"
			(at 0 0 180)
			(layer "F.SilkS")
			(hide yes)
			(effects
				(font
					(size 1.27 1.27)
				)
			)
		)
		(property "Value" ""
			(at 0 0 180)
			(layer "F.Fab")
			(effects
				(font
					(size 1.27 1.27)
				)
			)
		)
		(duplicate_pad_numbers_are_jumpers no)
		(fp_line
			(start 0.7874 0.4064)
			(end -0.7874 0.4064)
			(stroke
				(width 0.1524)
				(type default)
			)
			(layer "F.SilkS")
		)
		(fp_line
			(start 0.7874 -0.4064)
			(end 0.7874 0.4064)
			(stroke
				(width 0.1524)
				(type default)
			)
			(layer "F.SilkS")
		)
		(fp_line
			(start -0.7874 0.4064)
			(end -0.7874 -0.4064)
			(stroke
				(width 0.1524)
				(type default)
			)
			(layer "F.SilkS")
		)
		(fp_line
			(start -0.7874 -0.4064)
			(end 0.7874 -0.4064)
			(stroke
				(width 0.1524)
				(type default)
			)
			(layer "F.SilkS")
		)
		(fp_line
			(start 0.67945 0.3048)
			(end 0.120396 0.3048)
			(stroke
				(width 0.1)
				(type default)
			)
			(layer "F.Fab")
		)
		(fp_line
			(start 0.67945 -0.3048)
			(end 0.67945 0.3048)
			(stroke
				(width 0.1)
				(type default)
			)
			(layer "F.Fab")
		)
		(fp_line
			(start 0.12065 -0.2794)
			(end 0.12065 -0.3048)
			(stroke
				(width 0.1)
				(type default)
			)
			(layer "F.Fab")
		)
		(fp_line
			(start 0.12065 -0.3048)
			(end 0.67945 -0.3048)
			(stroke
				(width 0.1)
				(type default)
			)
			(layer "F.Fab")
		)
		(fp_line
			(start 0.120396 0.3048)
			(end 0.120396 0.2794)
			(stroke
				(width 0.1)
				(type default)
			)
			(layer "F.Fab")
		)
		(fp_line
			(start 0.120396 0.2794)
			(end -0.12065 0.2794)
			(stroke
				(width 0.1)
				(type default)
			)
			(layer "F.Fab")
		)
		(fp_line
			(start -0.12065 0.3048)
			(end -0.67945 0.3048)
			(stroke
				(width 0.1)
				(type default)
			)
			(layer "F.Fab")
		)
		(fp_line
			(start -0.12065 0.2794)
			(end -0.12065 0.3048)
			(stroke
				(width 0.1)
				(type default)
			)
			(layer "F.Fab")
		)
		(fp_line
			(start -0.12065 -0.2794)
			(end 0.12065 -0.2794)
			(stroke
				(width 0.1)
				(type default)
			)
			(layer "F.Fab")
		)
		(fp_line
			(start -0.12065 -0.305054)
			(end -0.12065 -0.2794)
			(stroke
				(width 0.1)
				(type default)
			)
			(layer "F.Fab")
		)
		(fp_line
			(start -0.67945 0.3048)
			(end -0.67945 -0.305054)
			(stroke
				(width 0.1)
				(type default)
			)
			(layer "F.Fab")
		)
		(fp_line
			(start -0.67945 -0.305054)
			(end -0.12065 -0.305054)
			(stroke
				(width 0.1)
				(type default)
			)
			(layer "F.Fab")
		)
		(pad "1" smd circle
			(at -0.40005 0 180)
			(size 0 0)
			(layers "F.Cu" "F.Mask" "F.Paste")
			(net "P3V3_AUX")
		)
		(pad "2" smd circle
			(at 0.40005 0 180)
			(size 0 0)
			(layers "F.Cu" "F.Mask" "F.Paste")
			(net "PWRGD_P3V3_AUX_R2")
		)
	)
	(footprint ""
		(layer "F.Cu")
		(at 170.23588 -435.955948)
		(property "Reference" "R3392"
			(at 0 0 0)
			(layer "F.SilkS")
			(hide yes)
			(effects
				(font
					(size 1.27 1.27)
				)
			)
		)
		(property "Value" ""
			(at 0 0 0)
			(layer "F.Fab")
			(effects
				(font
					(size 1.27 1.27)
				)
			)
		)
		(duplicate_pad_numbers_are_jumpers no)
		(fp_line
			(start -0.7874 -0.4064)
			(end 0.7874 -0.4064)
			(stroke
				(width 0.1524)
				(type default)
			)
			(layer "F.SilkS")
		)
		(fp_line
			(start -0.7874 0.4064)
			(end -0.7874 -0.4064)
			(stroke
				(width 0.1524)
				(type default)
			)
			(layer "F.SilkS")
		)
		(fp_line
			(start 0.7874 -0.4064)
			(end 0.7874 0.4064)
			(stroke
				(width 0.1524)
				(type default)
			)
			(layer "F.SilkS")
		)
		(fp_line
			(start 0.7874 0.4064)
			(end -0.7874 0.4064)
			(stroke
				(width 0.1524)
				(type default)
			)
			(layer "F.SilkS")
		)
		(fp_line
			(start -0.67945 -0.305054)
			(end -0.12065 -0.305054)
			(stroke
				(width 0.1)
				(type default)
			)
			(layer "F.Fab")
		)
		(fp_line
			(start -0.67945 0.3048)
			(end -0.67945 -0.305054)
			(stroke
				(width 0.1)
				(type default)
			)
			(layer "F.Fab")
		)
		(fp_line
			(start -0.12065 -0.305054)
			(end -0.12065 -0.2794)
			(stroke
				(width 0.1)
				(type default)
			)
			(layer "F.Fab")
		)
		(fp_line
			(start -0.12065 -0.2794)
			(end 0.12065 -0.2794)
			(stroke
				(width 0.1)
				(type default)
			)
			(layer "F.Fab")
		)
		(fp_line
			(start -0.12065 0.2794)
			(end -0.12065 0.3048)
			(stroke
				(width 0.1)
				(type default)
			)
			(layer "F.Fab")
		)
		(fp_line
			(start -0.12065 0.3048)
			(end -0.67945 0.3048)
			(stroke
				(width 0.1)
				(type default)
			)
			(layer "F.Fab")
		)
		(fp_line
			(start 0.120396 0.2794)
			(end -0.12065 0.2794)
			(stroke
				(width 0.1)
				(type default)
			)
			(layer "F.Fab")
		)
		(fp_line
			(start 0.120396 0.3048)
			(end 0.120396 0.2794)
			(stroke
				(width 0.1)
				(type default)
			)
			(layer "F.Fab")
		)
		(fp_line
			(start 0.12065 -0.3048)
			(end 0.67945 -0.3048)
			(stroke
				(width 0.1)
				(type default)
			)
			(layer "F.Fab")
		)
		(fp_line
			(start 0.12065 -0.2794)
			(end 0.12065 -0.3048)
			(stroke
				(width 0.1)
				(type default)
			)
			(layer "F.Fab")
		)
		(fp_line
			(start 0.67945 -0.3048)
			(end 0.67945 0.3048)
			(stroke
				(width 0.1)
				(type default)
			)
			(layer "F.Fab")
		)
		(fp_line
			(start 0.67945 0.3048)
			(end 0.120396 0.3048)
			(stroke
				(width 0.1)
				(type default)
			)
			(layer "F.Fab")
		)
		(pad "1" smd circle
			(at -0.40005 0)
			(size 0 0)
			(layers "F.Cu" "F.Mask" "F.Paste")
			(net "GPU_BASE_STBY_EN_BUF_R")
		)
		(pad "2" smd circle
			(at 0.40005 0)
			(size 0 0)
			(layers "F.Cu" "F.Mask" "F.Paste")
			(net "GPU_BASE_STBY_EN_BUF")
		)
	)
)
